INTEGER-PLACES         2
DECIMAL-PLACES         4
X-OFFSET               0.000000
Y-OFFSET               0.000000
FEEDRATE               1
COORDINATES            ABSOLUTE
OUTPUT-UNITS           ENGLISH
TOOL-ORDER             INCREASING
REPEAT-CODES           YES
SUPPRESS-LEAD-ZEROES   NO
SUPPRESS-TRAIL-ZEROES  NO
SUPPRESS-EQUAL         YES
TOOL-SELECT            NO
OPTIMIZE_DRILLING      NO
ENHANCED_EXCELLON      NO
TAPE-FILE              ncdrill.tap
HEADER                 none
LEADER                 12
CODE                   ASCII
SEPARATE               NO
DRILLING               LAYER-PAIR
BACKDRILL              NO
